# SCM (Grand Teton) — schematic netlist excerpt (pin names and nets, part order shuffled) for the footprints in the layout excerpt that follows; sources: Cadence DE-HDL packaged netlist, KiCad conversion of 12092022_DA0F0TMDCD0_F0T_Management_Board_D_brd_V3_OCP.brd

C154  Q_CAP  0.001UF 50V 10% EMPTY  pkg C0402  page 54 : A = PWRGD_P1V8_AUX_R ; B = GND
R405  Q_RES  33.2 1% CHIP  pkg 0402LF  page 13 : A = PD_BIOS_MUX_EN_R_N ; B = PD_BIOS_MUX_EN_N

(kicad_pcb
	(version 20260206)
	(generator "pcbnew")
	(generator_version "10.0")
	(general
		(thickness 1.6)
		(legacy_teardrops no)
	)
	(paper "A4")
	(title_block
		(title "12092022_DA0F0TMDCD0_F0T_Management_Board_D_brd_V3_OCP.brd")
		(comment 1 "Grand Teton / footprints 92-93 of 1440")
	)
	(layers
		(0 "F.Cu" signal "TOP")
		(4 "In1.Cu" signal "GND")
		(6 "In2.Cu" signal "IN1")
		(8 "In3.Cu" signal "GND1")
		(10 "In4.Cu" signal "IN2")
		(12 "In5.Cu" signal "VCC")
		(14 "In6.Cu" signal "VCC1")
		(16 "In7.Cu" signal "IN3")
		(18 "In8.Cu" signal "GND2")
		(20 "In9.Cu" signal "IN4")
		(22 "In10.Cu" signal "GND3")
		(2 "B.Cu" signal "BOTTOM")
		(9 "F.Adhes" user "F.Adhesive")
		(11 "B.Adhes" user "B.Adhesive")
		(13 "F.Paste" user "Package Geometry/Pastemask Top")
		(15 "B.Paste" user "Package Geometry/Pastemask Bottom")
		(5 "F.SilkS" user "Ref Des/Silkscreen Top")
		(7 "B.SilkS" user "Ref Des/Silkscreen Bottom")
		(1 "F.Mask" user "Board Geometry/Soldermask Top")
		(3 "B.Mask" user "Board Geometry/Soldermask Bottom")
		(17 "Dwgs.User" user "User.Drawings")
		(19 "Cmts.User" user "User.Comments")
		(21 "Eco1.User" user "User.Eco1")
		(23 "Eco2.User" user "User.Eco2")
		(25 "Edge.Cuts" user "Board Geometry/Outline")
		(27 "Margin" user)
		(31 "F.CrtYd" user "Package Geometry/Place Bound Top")
		(29 "B.CrtYd" user "Package Geometry/Place Bound Bottom")
		(35 "F.Fab" user "Ref Des/Assembly Top")
		(33 "B.Fab" user "Ref Des/Assembly Bottom")
	)
	(footprint ""
		(layer "F.Cu")
		(at 40.005 -58.547 90)
		(property "Reference" "C154"
			(at 0 0 90)
			(layer "F.SilkS")
			(hide yes)
			(effects
				(font
					(size 1.27 1.27)
				)
			)
		)
		(property "Value" ""
			(at 0 0 90)
			(layer "F.Fab")
			(effects
				(font
					(size 1.27 1.27)
				)
			)
		)
		(duplicate_pad_numbers_are_jumpers no)
		(fp_line
			(start 0.7874 -0.4064)
			(end 0.7874 0.4064)
			(stroke
				(width 0.1524)
				(type default)
			)
			(layer "F.SilkS")
		)
		(fp_line
			(start -0.7874 -0.4064)
			(end 0.7874 -0.4064)
			(stroke
				(width 0.1524)
				(type default)
			)
			(layer "F.SilkS")
		)
		(fp_line
			(start 0.7874 0.4064)
			(end -0.7874 0.4064)
			(stroke
				(width 0.1524)
				(type default)
			)
			(layer "F.SilkS")
		)
		(fp_line
			(start -0.7874 0.4064)
			(end -0.7874 -0.4064)
			(stroke
				(width 0.1524)
				(type default)
			)
			(layer "F.SilkS")
		)
		(fp_line
			(start -0.12065 -0.305054)
			(end -0.12065 -0.2794)
			(stroke
				(width 0.1)
				(type default)
			)
			(layer "F.Fab")
		)
		(fp_line
			(start -0.67945 -0.305054)
			(end -0.12065 -0.305054)
			(stroke
				(width 0.1)
				(type default)
			)
			(layer "F.Fab")
		)
		(fp_line
			(start 0.67945 -0.3048)
			(end 0.67945 0.3048)
			(stroke
				(width 0.1)
				(type default)
			)
			(layer "F.Fab")
		)
		(fp_line
			(start 0.12065 -0.3048)
			(end 0.67945 -0.3048)
			(stroke
				(width 0.1)
				(type default)
			)
			(layer "F.Fab")
		)
		(fp_line
			(start 0.12065 -0.2794)
			(end 0.12065 -0.3048)
			(stroke
				(width 0.1)
				(type default)
			)
			(layer "F.Fab")
		)
		(fp_line
			(start -0.12065 -0.2794)
			(end 0.12065 -0.2794)
			(stroke
				(width 0.1)
				(type default)
			)
			(layer "F.Fab")
		)
		(fp_line
			(start 0.120396 0.2794)
			(end -0.12065 0.2794)
			(stroke
				(width 0.1)
				(type default)
			)
			(layer "F.Fab")
		)
		(fp_line
			(start -0.12065 0.2794)
			(end -0.12065 0.3048)
			(stroke
				(width 0.1)
				(type default)
			)
			(layer "F.Fab")
		)
		(fp_line
			(start 0.67945 0.3048)
			(end 0.120396 0.3048)
			(stroke
				(width 0.1)
				(type default)
			)
			(layer "F.Fab")
		)
		(fp_line
			(start 0.120396 0.3048)
			(end 0.120396 0.2794)
			(stroke
				(width 0.1)
				(type default)
			)
			(layer "F.Fab")
		)
		(fp_line
			(start -0.12065 0.3048)
			(end -0.67945 0.3048)
			(stroke
				(width 0.1)
				(type default)
			)
			(layer "F.Fab")
		)
		(fp_line
			(start -0.67945 0.3048)
			(end -0.67945 -0.305054)
			(stroke
				(width 0.1)
				(type default)
			)
			(layer "F.Fab")
		)
		(pad "1" smd circle
			(at -0.40005 0 90)
			(size 0 0)
			(layers "F.Cu" "F.Mask" "F.Paste")
			(net "PWRGD_P1V8_AUX_R")
		)
		(pad "2" smd circle
			(at 0.40005 0 90)
			(size 0 0)
			(layers "F.Cu" "F.Mask" "F.Paste")
			(net "GND")
		)
	)
	(footprint ""
		(layer "F.Cu")
		(at 36.07054 -45.50664 180)
		(property "Reference" "R405"
			(at 0 0 180)
			(layer "F.SilkS")
			(hide yes)
			(effects
				(font
					(size 1.27 1.27)
				)
			)
		)
		(property "Value" ""
			(at 0 0 180)
			(layer "F.Fab")
			(effects
				(font
					(size 1.27 1.27)
				)
			)
		)
		(duplicate_pad_numbers_are_jumpers no)
		(fp_line
			(start 0.7874 0.4064)
			(end -0.7874 0.4064)
			(stroke
				(width 0.1524)
				(type default)
			)
			(layer "F.SilkS")
		)
		(fp_line
			(start 0.7874 -0.4064)
			(end 0.7874 0.4064)
			(stroke
				(width 0.1524)
				(type default)
			)
			(layer "F.SilkS")
		)
		(fp_line
			(start -0.7874 0.4064)
			(end -0.7874 -0.4064)
			(stroke
				(width 0.1524)
				(type default)
			)
			(layer "F.SilkS")
		)
		(fp_line
			(start -0.7874 -0.4064)
			(end 0.7874 -0.4064)
			(stroke
				(width 0.1524)
				(type default)
			)
			(layer "F.SilkS")
		)
		(fp_line
			(start 0.67945 0.3048)
			(end 0.120396 0.3048)
			(stroke
				(width 0.1)
				(type default)
			)
			(layer "F.Fab")
		)
		(fp_line
			(start 0.67945 -0.3048)
			(end 0.67945 0.3048)
			(stroke
				(width 0.1)
				(type default)
			)
			(layer "F.Fab")
		)
		(fp_line
			(start 0.12065 -0.2794)
			(end 0.12065 -0.3048)
			(stroke
				(width 0.1)
				(type default)
			)
			(layer "F.Fab")
		)
		(fp_line
			(start 0.12065 -0.3048)
			(end 0.67945 -0.3048)
			(stroke
				(width 0.1)
				(type default)
			)
			(layer "F.Fab")
		)
		(fp_line
			(start 0.120396 0.3048)
			(end 0.120396 0.2794)
			(stroke
				(width 0.1)
				(type default)
			)
			(layer "F.Fab")
		)
		(fp_line
			(start 0.120396 0.2794)
			(end -0.12065 0.2794)
			(stroke
				(width 0.1)
				(type default)
			)
			(layer "F.Fab")
		)
		(fp_line
			(start -0.12065 0.3048)
			(end -0.67945 0.3048)
			(stroke
				(width 0.1)
				(type default)
			)
			(layer "F.Fab")
		)
		(fp_line
			(start -0.12065 0.2794)
			(end -0.12065 0.3048)
			(stroke
				(width 0.1)
				(type default)
			)
			(layer "F.Fab")
		)
		(fp_line
			(start -0.12065 -0.2794)
			(end 0.12065 -0.2794)
			(stroke
				(width 0.1)
				(type default)
			)
			(layer "F.Fab")
		)
		(fp_line
			(start -0.12065 -0.305054)
			(end -0.12065 -0.2794)
			(stroke
				(width 0.1)
				(type default)
			)
			(layer "F.Fab")
		)
		(fp_line
			(start -0.67945 0.3048)
			(end -0.67945 -0.305054)
			(stroke
				(width 0.1)
				(type default)
			)
			(layer "F.Fab")
		)
		(fp_line
			(start -0.67945 -0.305054)
			(end -0.12065 -0.305054)
			(stroke
				(width 0.1)
				(type default)
			)
			(layer "F.Fab")
		)
		(pad "1" smd circle
			(at -0.40005 0 180)
			(size 0 0)
			(layers "F.Cu" "F.Mask" "F.Paste")
			(net "PD_BIOS_MUX_EN_R_N")
		)
		(pad "2" smd circle
			(at 0.40005 0 180)
			(size 0 0)
			(layers "F.Cu" "F.Mask" "F.Paste")
			(net "PD_BIOS_MUX_EN_N")
		)
	)
)
